FILE_TYPE = CONNECTIVITY;
{Allegro Design Entry HDL 16.6-p007 (v16-6-112F) 10/10/2012}
"PAGE_NUMBER" = 213;
0"NC";
1"P3V3_STBY\g";
2"GND\g";
3"GND\g";
4"GND\g";
5"GND\g";
6"P3V3_STBY\g";
7"PVCCIO_CPU1\g";
8"PVCCIO_CPU1\g";
9"GND\g";
10"GND\g";
11"GND\g";
12"GND\g";
13"GND\g";
14"GND\g";
15"VR_FET_SW_P12V_STBY_PVCCIN_CPU0\g";
16"VR_PVCCIO_CPU1_VINSEN";
17"SVID_DIO0_CPU1_R";
18"VR_PVCCIO_CPU1_VDD"VOLTAGE"3.3";
19"PWRGD_PVCCIO_CPU1";
20"IRQ_PVCCIO_CPU1_VRHOT_N";
21"VR_PVCCIO_CPU1_VD12";
22"SVID_ALERT0_CPU1_R_N";
23"VR_PVCCIO_CPU1_PWM1"VOLTAGE"3.6";
24"PWRGD_PVCCIO_CPU1_R";
25"PU_VR_PVCCIO_CPU1_FAULT1";
26"TP_VR_PVCCIO_CPU1_MP0";
27"TP_VR_PVCCIO_CPU1_MP3";
28"TP_VR_PVCCIO_CPU1_MP2";
29"TP_VR_PVCCIO_CPU1_MP1";
30"NC_PVCCIO_CPU1_DNC0";
31"NC_PVCCIO_CPU1_DNC1";
32"NC_PVCCIO_CPU1_DNC2";
33"NC_PVCCIO_CPU1_DNC3";
34"NC_PVCCIO_CPU1_DNC4";
35"TP_PVCCIO_CPU1_BPWM1";
36"TP_PVCCIO_CPU1_PINALRT_N";
37"SVID_ALERT_PVCCIO_CPU1";
38"VR_PVCCIO_CPU1_EN"VOLTAGE"3.3";
39"SVID_CLK0_CPU1_R";
40"SVID_CLK_PVCCIO_CPU1";
41"TP_PVCCIO_CPU1_RESET_N";
42"VR_PVCCIO_CPU1_XADDR1"VOLTAGE"3.3";
43"TP_PVCCIO_CPU1_BTSEN";
44"TP_PVCCIO_CPU1_BIREF1";
45"TP_PVCCIO_CPU1_BVSEN";
46"TP_PVCCIO_CPU1_BVREF";
47"VSENSE_PVCCIO_CPU1_AVSN";
48"VR_PVCCIO_CPU1_AVSP"VOLTAGE"1.05";
49"SMB_VR_SDA_PVCCIO_CPU1";
50"SMB_VR_SCL_PVCCIO_CPU1";
51"SVID_VDIO_PVCCIO_CPU1";
52"TP_VR_PVCCIO_CPU1_AIINSEN";
53"VR_PVCCIO_CPU1_XADDR2"VOLTAGE"3.3";
54"VR_PVCCIO_CPU1_AIREF1";
55"ISENSE_PVCCIO_CPU1_PH1_IMON";
56"VR_PVCCIO_CPU1_VINSEN";
57"FM_PVCCIO_CPU1_EN";
58"A_TSENSE_PVCCIO_CPU1";
59"VR_PVCCIO_CPU1_VD12";
60"SMB_VR_STBY_LVC3_SCL";
61"SMB_VR_STBY_LVC3_SDA";
62"VR_PVCCIO_CPU1_VD12";
63"VSENSE_PVCCIO_CPU1_AVSP";
%"P3V3_STBY"
"1","(1875,4725)","0","mstr_symbols","I1";
;
VOLTAGE"3.3V"
SIZE"1B"
CDS_LIB"mstr_symbols"
BODY_TYPE"PLUMBING"
HDL_POWER"P3V3_STBY";
"G\NAC"1;
%"GND"
"1","(2425,1275)","0","mstr_symbols","I10";
;
HDL_POWER"GND"
VOLTAGE"0"
CDS_LIB"mstr_symbols"
SIZE"1B"
BODY_TYPE"PLUMBING"
ROOM"PVCCIO_CPU1";
"A\NAC"2;
%"CAP_A"
"1","(2025,1575)","0","dev_discrete","I11";
;
ROOM"PVCCIO_CPU1"
CDS_LOCATION"C4D32"
CDS_SEC"1"
SEC_TYPE"0402V"
SEC"1"
CDS_LIB"dev_discrete"
LOCATION"C4D32"
VALUE"0.1UF"
VOLTAGE"16V"
TOLERANCE"10%"
PART_NUMBER"A36096-030"
MATERIAL"X7R"
PACK_TYPE"0402V";
"B"
$PN"2"3;
"A"
$PN"1"21;
%"GND"
"1","(2025,1375)","0","mstr_symbols","I12";
;
SIZE"1B"
HDL_POWER"GND"
BODY_TYPE"PLUMBING"
VOLTAGE"0"
CDS_LIB"mstr_symbols"
ROOM"PVCCIO_CPU1";
"A\NAC"3;
%"RES"
"1","(1950,3575)","0","mstr_discrete","I13";
;
CDS_SEC"1"
SEC_TYPE"0402"
SEC"1"
CDS_LOCATION"R4D46"
ROOM"PVCCIO_CPU1"
CDS_LIB"mstr_discrete"
PACK_TYPE"0402"
PART_NUMBER"G21796-250"
TOLERANCE"1.0%"
MATERIAL"CHIP"
LOCATION"R4D46"
VALUE"22.1"
WATTAGE"1/16W";
"B"
$PN"2"19;
"A"
$PN"1"24;
%"RES"
"2","(1600,4075)","0","mstr_discrete","I14";
;
CDS_SEC"1"
CDS_LOCATION"R6P49"
SEC_TYPE"0402"
SEC"1"
CDS_LIB"mstr_discrete"
ROOM"PVCCIO_CPU1"
LOCATION"R6P49"
VALUE"2.26K"
TOLERANCE"1.0%"
PART_NUMBER"G21796-311"
MATERIAL"EMPTY"
PACK_TYPE"0402"
WATTAGE"1/16W";
"A"
$PN"1"1;
"B"
$PN"2"25;
%"RES"
"2","(950,4050)","0","mstr_discrete","I15";
;
CDS_SEC"1"
$SEC"1"
CDS_LOCATION"R4D42"
ROOM"PVCCIO_CPU1"
CDS_LIB"mstr_discrete"
LOCATION"R4D42"
VALUE"1.00K"
TOLERANCE"1%"
PART_NUMBER"G21796-026"
PACK_TYPE"0402"
MATERIAL"CHIP"
WATTAGE"1/16W";
"A"
$PN"1"1;
"B"
$PN"2"24;
%"RES"
"1","(1375,3125)","0","mstr_discrete","I16";
;
CDS_SEC"1"
SEC_TYPE"0402"
SEC"1"
CDS_LIB"mstr_discrete"
CDS_LOCATION"R4D56"
ROOM"PVCCIO_CPU1"
MATERIAL"CHIP"
PACK_TYPE"0402"
LOCATION"R4D56"
TOLERANCE"5%"
VALUE"0.0"
WATTAGE"1/16W"
PART_NUMBER"G21497-005";
"B"
$PN"2"22;
"A"
$PN"1"37;
%"CAP_A"
"1","(150,4150)","0","dev_discrete","I17";
;
ROOM"PVCCIO_CPU1"
CDS_SEC"1"
$SEC"1"
CDS_LOCATION"C4D36"
CDS_LIB"dev_discrete"
LOCATION"C4D36"
VALUE"1.0UF"
TOLERANCE"10%"
VOLTAGE"6.3V"
MATERIAL"X6S"
PART_NUMBER"D97712-004"
PACK_TYPE"0402V";
"B"
$PN"2"4;
"A"
$PN"1"18;
%"GND"
"1","(150,3950)","0","mstr_symbols","I18";
;
HDL_POWER"GND"
VOLTAGE"0"
CDS_LIB"mstr_symbols"
SIZE"1B"
BODY_TYPE"PLUMBING"
ROOM"PVCCIO_CPU1";
"A\NAC"4;
%"GND"
"1","(1000,1875)","0","mstr_symbols","I21";
;
HDL_POWER"GND"
SIZE"1B"
VOLTAGE"0"
CDS_LIB"mstr_symbols"
BODY_TYPE"PLUMBING"
ROOM"PVCCIO_CPU1";
"A\NAC"5;
%"P3V3_STBY"
"1","(-550,4825)","0","mstr_symbols","I24";
;
SIZE"1B"
CDS_LIB"mstr_symbols"
VOLTAGE"3.3V"
BODY_TYPE"PLUMBING"
HDL_POWER"P3V3_STBY";
"G\NAC"6;
%"RES"
"2","(-550,4500)","0","mstr_discrete","I25";
;
CDS_SEC"1"
$SEC"1"
CDS_LOCATION"R4D47"
ROOM"PVCCIO_CPU1"
CDS_LIB"mstr_discrete"
LOCATION"R4D47"
PART_NUMBER"G21497-005"
VALUE"0.0"
TOLERANCE"5%"
PACK_TYPE"0402"
MATERIAL"CHIP"
WATTAGE"1/16W";
"A"
$PN"1"6;
"B"
$PN"2"18;
%"PVCCIO_CPU1"
"1","(-1375,4900)","0","mstr_symbols","I26";
;
HDL_POWER"PVCCIO_CPU1"
BODY_TYPE"PLUMBING"
CDS_LIB"mstr_symbols"
VOLTAGE"1.1V";
"G\NAC"7;
%"RES"
"2","(-1375,4475)","0","mstr_discrete","I27";
;
ROOM"PVCCIO_CPU1"
$SEC"1"
CDS_SEC"1"
CDS_LOCATION"R6P35"
CDS_LIB"mstr_discrete"
LOCATION"R6P35"
MATERIAL"EMPTY"
PART_NUMBER"G21796-017"
VALUE"100.0"
TOLERANCE"1%"
PACK_TYPE"0402"
WATTAGE"1/16W";
"A"
$PN"1"7;
"B"
$PN"2"17;
%"PVCCIO_CPU1"
"1","(-2050,4875)","0","mstr_symbols","I28";
;
VOLTAGE"1.1V"
CDS_LIB"mstr_symbols"
BODY_TYPE"PLUMBING"
HDL_POWER"PVCCIO_CPU1";
"G\NAC"8;
%"RES"
"2","(-2050,4425)","0","mstr_discrete","I30";
;
CDS_SEC"1"
SEC_TYPE"0402"
SEC"1"
ROOM"PVCCIO_CPU1"
CDS_LOCATION"R6P33"
CDS_LIB"mstr_discrete"
PART_NUMBER"G21796-203"
LOCATION"R6P33"
VALUE"110"
WATTAGE"1/16W"
TOLERANCE"1%"
MATERIAL"EMPTY"
PACK_TYPE"0402";
"A"
$PN"1"8;
"B"
$PN"2"39;
%"RES"
"2","(-2425,4700)","0","mstr_discrete","I31";
;
CDS_SEC"1"
SEC_TYPE"0402"
SEC"1"
ROOM"PVCCIO_CPU1"
CDS_LIB"mstr_discrete"
CDS_LOCATION"R4D60"
LOCATION"R4D60"
VALUE"100.0K"
MATERIAL"CHIP"
WATTAGE"1/16W"
TOLERANCE"1%"
PART_NUMBER"G21796-160"
PACK_TYPE"0402";
"A"
$PN"1"15;
"B"
$PN"2"16;
%"RES"
"2","(-2425,4250)","0","mstr_discrete","I32";
;
CDS_SEC"1"
SEC_TYPE"0402"
SEC"1"
CDS_LOCATION"R4D57"
ROOM"PVCCIO_CPU1"
CDS_LIB"mstr_discrete"
LOCATION"R4D57"
PART_NUMBER"G21796-003"
VALUE"1.5K"
MATERIAL"CHIP"
WATTAGE"1/16W"
TOLERANCE"1%"
PACK_TYPE"0402";
"A"
$PN"1"16;
"B"
$PN"2"12;
%"CAP"
"1","(-2650,4250)","2","mstr_discrete","I33";
;
CDS_SEC"1"
ROOM"PVCCIO_CPU1"
SEC_TYPE"0402LF"
SEC"1"
CDS_LOCATION"C4D40"
CDS_LIB"mstr_discrete"
TOLERANCE"10%"
VOLTAGE"50V"
MATERIAL"X7R"
LOCATION"C4D40"
PART_NUMBER"A36096-046"
VALUE"1000PF"
PACK_TYPE"0402LF";
"A"
$PN"1"16;
"B"
$PN"2"13;
%"CAP_A"
"1","(-250,4150)","0","dev_discrete","I35";
;
$SEC"1"
CDS_SEC"1"
ROOM"PVCCIO_CPU1"
CDS_LOCATION"C4D38"
CDS_LIB"dev_discrete"
PART_NUMBER"A36096-030"
LOCATION"C4D38"
VALUE"0.1UF"
TOLERANCE"10%"
VOLTAGE"16V"
MATERIAL"X7R"
PACK_TYPE"0402V";
"B"
$PN"2"9;
"A"
$PN"1"18;
%"GND"
"1","(-250,3950)","0","mstr_symbols","I36";
;
HDL_POWER"GND"
VOLTAGE"0"
CDS_LIB"mstr_symbols"
SIZE"1B"
BODY_TYPE"PLUMBING"
ROOM"PVCCIO_CPU1";
"A\NAC"9;
%"RES"
"1","(-1175,2925)","0","mstr_discrete","I37";
;
CDS_SEC"1"
$SEC"1"
ROOM"PVCCIO_CPU1"
CDS_LOCATION"R4D54"
CDS_LIB"mstr_discrete"
PACK_TYPE"0402"
LOCATION"R4D54"
TOLERANCE"5%"
MATERIAL"CHIP"
PART_NUMBER"G21497-005"
VALUE"0.0"
WATTAGE"1/16W";
"B"
$PN"2"51;
"A"
$PN"1"17;
%"RES"
"1","(-1175,2425)","0","mstr_discrete","I38";
;
$SEC"1"
CDS_SEC"1"
ROOM"PVCCIO_CPU1"
CDS_LIB"mstr_discrete"
CDS_LOCATION"R4D44"
PART_NUMBER"G21796-173"
LOCATION"R4D44"
TOLERANCE"1%"
PACK_TYPE"0402"
MATERIAL"CHIP"
VALUE"20.0"
WATTAGE"1/16W";
"B"
$PN"2"49;
"A"
$PN"1"61;
%"RES"
"1","(-1500,2375)","0","mstr_discrete","I39";
;
CDS_LIB"mstr_discrete"
CDS_SEC"1"
$SEC"1"
CDS_LOCATION"R4D43"
ROOM"PVCCIO_CPU1"
PACK_TYPE"0402"
TOLERANCE"1%"
MATERIAL"CHIP"
LOCATION"R4D43"
PART_NUMBER"G21796-173"
VALUE"20.0"
WATTAGE"1/16W";
"B"
$PN"2"50;
"A"
$PN"1"60;
%"RES"
"2","(-850,1325)","0","mstr_discrete","I42";
;
CDS_SEC"1"
BOM_COST"PROC_VRD_PVCCIO_CPU1"
SEC_TYPE"0402"
ROOM"PVCCIO_CPU1"
CDS_LOCATION"R4D64"
SEC"1"
CDS_LIB"mstr_discrete"
LOCATION"R4D64"
PART_NUMBER"G21796-043"
VALUE"3.16K"
TOLERANCE"1%"
PACK_TYPE"0402"
MATERIAL"CHIP"
WATTAGE"1/16W";
"A"
$PN"1"42;
"B"
$PN"2"10;
%"GND"
"1","(-850,750)","0","mstr_symbols","I44";
;
HDL_POWER"GND"
VOLTAGE"0"
CDS_LIB"mstr_symbols"
BODY_TYPE"PLUMBING"
SIZE"1B"
ROOM"PVCCIO_CPU1";
"A\NAC"10;
%"GND"
"1","(-950,2025)","0","mstr_symbols","I45";
;
HDL_POWER"GND"
ROOM"PVCCIO_CPU1"
VOLTAGE"0"
CDS_LIB"mstr_symbols"
SIZE"1B"
BODY_TYPE"PLUMBING";
"A\NAC"11;
%"RES"
"1","(-1825,3925)","0","mstr_discrete","I46";
;
CDS_SEC"1"
SEC_TYPE"0402"
SEC"1"
CDS_LOCATION"R4D51"
ROOM"PVCCIO_CPU1"
CDS_LIB"mstr_discrete"
LOCATION"R4D51"
PACK_TYPE"0402"
TOLERANCE"1%"
MATERIAL"CHIP"
WATTAGE"1/16W"
PART_NUMBER"G21796-009"
VALUE"150.0";
"B"
$PN"2"40;
"A"
$PN"1"39;
%"GND"
"1","(-2425,4000)","0","mstr_symbols","I47";
;
HDL_POWER"GND"
ROOM"PVCCIO_CPU1"
VOLTAGE"0"
CDS_LIB"mstr_symbols"
SIZE"1B"
BODY_TYPE"PLUMBING";
"A\NAC"12;
%"GND"
"1","(-2650,4000)","0","mstr_symbols","I49";
;
HDL_POWER"GND"
ROOM"PVCCIO_CPU1"
VOLTAGE"0"
SIZE"1B"
CDS_LIB"mstr_symbols"
BODY_TYPE"PLUMBING";
"A\NAC"13;
%"RES"
"2","(2175,4050)","0","mstr_discrete","I63";
;
CDS_SEC"1"
$SEC"1"
CDS_LOCATION"R4D49"
CDS_LIB"mstr_discrete"
LOCATION"R4D49"
VALUE"1.00K"
TOLERANCE"1%"
PACK_TYPE"0402"
MATERIAL"CHIP"
WATTAGE"1/16W"
PART_NUMBER"G21796-026";
"A"
$PN"1"1;
"B"
$PN"2"20;
%"RES"
"2","(-525,1325)","0","mstr_discrete","I65";
;
$SEC"1"
CDS_SEC"1"
CDS_LOCATION"R4E2"
CDS_LIB"mstr_discrete"
WATTAGE"1/16W"
MATERIAL"CHIP"
PACK_TYPE"0402"
TOLERANCE"1%"
VALUE"3.16K"
PART_NUMBER"G21796-043"
LOCATION"R4E2";
"A"
$PN"1"53;
"B"
$PN"2"10;
%"CAP"
"1","(1750,2700)","0","mstr_discrete","I73";
;
CDS_SEC"1"
ROOM"PVCCIO_CPU1_VR"
CDS_LOCATION"C4D33"
SEC"1"
SEC_TYPE"0402LF"
CDS_LIB"mstr_discrete"
PART_NUMBER"A36096-046"
TOLERANCE"10%"
VALUE"1000PF"
LOCATION"C4D33"
VOLTAGE"50V"
MATERIAL"X7R"
PACK_TYPE"0402LF";
"A"
$PN"1"24;
"B"
$PN"2"14;
%"GND"
"1","(1750,2500)","0","mstr_symbols","I74";
;
HDL_POWER"GND"
VOLTAGE"0"
CDS_LIB"mstr_symbols"
SIZE"1B"
BODY_TYPE"PLUMBING"
ROOM"PVCCIO_CPU1";
"A\NAC"14;
%"CAP"
"1","(-2075,1725)","0","mstr_discrete","I83";
;
CDS_SEC"1"
SEC_TYPE"0402LF"
SEC"1"
CDS_LOCATION"C4D44"
ROOM"PVCCIO_CPU1"
CDS_LIB"mstr_discrete"
LOCATION"C4D44"
PART_NUMBER"A36096-050"
VALUE"220PF"
TOLERANCE"10%"
PACK_TYPE"0402LF"
VOLTAGE"50V"
MATERIAL"X7R";
"A"
$PN"1"48;
"B"
$PN"2"47;
%"RES"
"1","(-2325,1925)","0","mstr_discrete","I84";
;
CDS_SEC"1"
SEC_TYPE"0402"
SEC"1"
ROOM"PVCCIO_CPU1"
CDS_LIB"mstr_discrete"
CDS_LOCATION"R4E7"
PACK_TYPE"0402"
MATERIAL"CHIP"
LOCATION"R4E7"
PART_NUMBER"G21796-066"
VALUE"10.0"
TOLERANCE"1%"
WATTAGE"1/16W";
"B"
$PN"2"48;
"A"
$PN"1"63;
%"CAP_A"
"1","(2425,1575)","0","dev_discrete","I9";
;
SEC"1"
SEC_TYPE"0402V"
ROOM"PVCCIO_CPU1"
CDS_SEC"1"
CDS_LOCATION"C4D31"
CDS_LIB"dev_discrete"
LOCATION"C4D31"
PART_NUMBER"D97712-004"
VALUE"1.0UF"
TOLERANCE"10%"
PACK_TYPE"0402V"
VOLTAGE"6.3V"
MATERIAL"X6S";
"B"
$PN"2"2;
"A"
$PN"1"21;
%"RES"
"1","(-1925,3225)","0","mstr_discrete","I90";
;
CDS_SEC"1"
$SEC"1"
ROOM"PVCCIN_CPU0_VR"
CDS_LIB"mstr_discrete"
CDS_LOCATION"R6P41"
PACK_TYPE"0402"
LOCATION"R6P41"
TOLERANCE"5%"
MATERIAL"CHIP"
PART_NUMBER"G21497-005"
VALUE"0.0"
WATTAGE"1/16W";
"B"
$PN"2"38;
"A"
$PN"1"57;
%"RES"
"2","(-1025,4275)","0","mstr_discrete","I91";
;
BOM_COST"SM_CONTROLLER"
CDS_SEC"1"
$SEC"1"
CDS_LOCATION"R6P40"
ROOM"BMC"
CDS_LIB"mstr_discrete"
PART_NUMBER"G21796-010"
LOCATION"R6P40"
VALUE"100.0K"
MATERIAL"EMPTY"
PACK_TYPE"0402"
WATTAGE"1/16W"
TOLERANCE"1%";
"A"
$PN"1"6;
"B"
$PN"2"38;
%"UNIVERSAL_POWER"
"1","(-2425,4975)","0","mstr_symbols","I92";
;
CDS_LIB"mstr_symbols"
HDL_POWER"VR_FET_SW_P12V_STBY_PVCCIN_CPU0";
"A"15;
%"RES"
"1","(-2425,3675)","0","mstr_discrete","I94";
;
CDS_SEC"1"
$SEC"1"
CDS_LIB"mstr_discrete"
ROOM"PVCCIN_CPU0_VR"
CDS_LOCATION"R4D45"
LOCATION"R4D45"
TOLERANCE"5%"
PACK_TYPE"0402"
MATERIAL"CHIP"
PART_NUMBER"G21497-005"
VALUE"0.0"
WATTAGE"1/16W";
"B"
$PN"2"54;
"A"
$PN"1"62;
%"PXE1110B"
"1","(175,2825)","0","mstr_controller","I96";
;
CDS_SEC"1"
CDS_LIB"mstr_controller"
CDS_LMAN_SYM_OUTLINE"-400,850,400,-850"
PACK_TYPE"QFN"
SEC_TYPE"QFN"
SEC"1"
CDS_LOCATION"EU4D5"
PART_NUMBER"H89187-001"
LOCATION"EU4D5"
MATERIAL"IC";
"AVREN"
$PN"10"38;
"AVRRDY"
$PN"9"24;
"MP4"
$PN"32"25;
"MP3"
$PN"31"27;
"MP2"
$PN"18"28;
"MP1"
$PN"14"29;
"MP0"
$PN"13"26;
"DNC<3>"
$PN"24"33;
"VD12"
$PN"40"59;
"IINSEN"
$PN"38"52;
"VINSEN"
$PN"37"56;
"BVREF"
$PN"30"46;
"BVSEN"
$PN"29"45;
"AVREF"
$PN"20"47;
"AVSEN"
$PN"19"48;
"VALRT_N \B"
$PN"17"37;
"PINALRT_N \B"
$PN"12"36;
"VRHOT_N \B"
$PN"11"20;
"GND<1>"
$PN"23"5;
"GND<0>"
$PN"27"5;
"DNC<4>"
$PN"28"34;
"DNC<2>"
$PN"4"32;
"DNC<1>"
$PN"2"31;
"DNC<0>"
$PN"1"30;
"BIREF1"
$PN"25"44;
"BISEN1"
$PN"26"11;
"BTSEN"
$PN"34"43;
"VDD"
$PN"39"18;
"AIREF1"
$PN"21"54;
"AISEN1"
$PN"22"55;
"ATSEN"
$PN"35"58;
"XADDR2"
$PN"33"53;
"XADDR1"
$PN"36"42;
"RESET_N \B"
$PN"8"41;
"VDIO"
$PN"16"51;
"VCLK"
$PN"15"40;
"SCL"
$PN"7"50;
"SDA"
$PN"6"49;
"APWM1"
$PN"5"23;
"BPWM1"
$PN"3"35;
"THPAD"
$PN"41"5;
END.
